(kicad_pcb
	(version 20241229)
	(generator "pcbnew")
	(generator_version "9.0")
	(general
		(thickness 1.59)
		(legacy_teardrops no)
	)
	(paper "A3")
	(title_block
		(title "usb-c-power-adapter")
		(date "2025-06-24")
		(rev "1.1.2")
		(company "Antmicro")
		(comment 9 "footprints 73-78 of 122")
	)
	(layers
		(0 "F.Cu" signal)
		(4 "In1.Cu" signal)
		(6 "In2.Cu" signal)
		(2 "B.Cu" signal)
		(9 "F.Adhes" user "F.Adhesive")
		(11 "B.Adhes" user "B.Adhesive")
		(13 "F.Paste" user)
		(15 "B.Paste" user)
		(5 "F.SilkS" user "F.Silkscreen")
		(7 "B.SilkS" user "B.Silkscreen")
		(1 "F.Mask" user)
		(3 "B.Mask" user)
		(17 "Dwgs.User" user "User.Drawings")
		(19 "Cmts.User" user "User.Comments")
		(21 "Eco1.User" user "User.Eco1")
		(23 "Eco2.User" user "User.Eco2")
		(25 "Edge.Cuts" user)
		(27 "Margin" user)
		(31 "F.CrtYd" user "F.Courtyard")
		(29 "B.CrtYd" user "B.Courtyard")
		(35 "F.Fab" user)
		(33 "B.Fab" user)
	)
	(footprint "antmicro-footprints:C_Pol_Vishay-T59-EE"
		(layer "F.Cu")
		(at 84.676 95.55 -90)
		(property "Reference" "C44"
			(at -5.6 1.276 0)
			(unlocked yes)
			(layer "F.SilkS")
			(effects
				(font
					(size 0.7 0.7)
					(thickness 0.15)
				)
				(justify left bottom)
			)
		)
		(property "Value" "C_Pol_150u_30V_Vishay-T59-EE"
			(at -5.08 5.08 270)
			(unlocked yes)
			(layer "F.Fab")
			(effects
				(font
					(size 0.7 0.7)
					(thickness 0.15)
				)
				(justify left bottom)
			)
		)
		(property "Datasheet" "https://www.vishay.com/docs/40191/t59.pdf"
			(at 0 0 270)
			(layer "F.Fab")
			(hide yes)
			(effects
				(font
					(size 1.27 1.27)
					(thickness 0.15)
				)
			)
		)
		(property "Description" "Tantalum Capacitors - Polymer 150uF 30volts 20% 75mohms maxESR"
			(at 0 0 270)
			(layer "F.Fab")
			(hide yes)
			(effects
				(font
					(size 1.27 1.27)
					(thickness 0.15)
				)
			)
		)
		(property "MPN" "T59EE157M030C0075"
			(at 0 0 270)
			(unlocked yes)
			(layer "F.Fab")
			(hide yes)
			(effects
				(font
					(size 1 1)
					(thickness 0.15)
				)
			)
		)
		(property "Manufacturer" "Vishay"
			(at 0 0 270)
			(unlocked yes)
			(layer "F.Fab")
			(hide yes)
			(effects
				(font
					(size 1 1)
					(thickness 0.15)
				)
			)
		)
		(property "Voltage" "30V"
			(at 0 0 270)
			(unlocked yes)
			(layer "F.Fab")
			(hide yes)
			(effects
				(font
					(size 1 1)
					(thickness 0.15)
				)
			)
		)
		(property "Val" "150u"
			(at 0 0 270)
			(unlocked yes)
			(layer "F.Fab")
			(hide yes)
			(effects
				(font
					(size 1 1)
					(thickness 0.15)
				)
			)
		)
		(property "Author" "Antmicro"
			(at 0 0 270)
			(unlocked yes)
			(layer "F.Fab")
			(hide yes)
			(effects
				(font
					(size 1 1)
					(thickness 0.15)
				)
			)
		)
		(property "License" "Apache-2.0"
			(at 0 0 270)
			(unlocked yes)
			(layer "F.Fab")
			(hide yes)
			(effects
				(font
					(size 1 1)
					(thickness 0.15)
				)
			)
		)
		(property "Dielectric" "template_dielectric"
			(at 0 0 270)
			(unlocked yes)
			(layer "F.Fab")
			(hide yes)
			(effects
				(font
					(size 1 1)
					(thickness 0.15)
				)
			)
		)
		(sheetname "/DC-DC Converters/")
		(sheetfile "dc-dc_converters.kicad_sch")
		(attr smd)
		(fp_line
			(start -2 2.25)
			(end 2 2.25)
			(stroke
				(width 0.15)
				(type solid)
			)
			(layer "F.SilkS")
		)
		(fp_line
			(start -2 -2.25)
			(end 2 -2.25)
			(stroke
				(width 0.15)
				(type solid)
			)
			(layer "F.SilkS")
		)
		(fp_line
			(start -3.5 -2.8)
			(end -3.5 -3.2)
			(stroke
				(width 0.15)
				(type solid)
			)
			(layer "F.SilkS")
		)
		(fp_line
			(start -3.7 -3)
			(end -3.3 -3)
			(stroke
				(width 0.15)
				(type solid)
			)
			(layer "F.SilkS")
		)
		(fp_rect
			(start -4.9 -2.9)
			(end 4.9 2.9)
			(stroke
				(width 0.05)
				(type solid)
			)
			(fill no)
			(layer "F.CrtYd")
		)
		(fp_rect
			(start -3.75 -2.25)
			(end 3.75 2.25)
			(stroke
				(width 0.15)
				(type solid)
			)
			(fill no)
			(layer "F.Fab")
		)
		(pad "1" smd trapezoid
			(at -3.4 0 270)
			(size 2.5 5.3)
			(layers "F.Cu" "F.Mask" "F.Paste")
			(net 12 "Net-(U2-V_{CIN})")
			(pintype "passive")
		)
		(pad "2" smd trapezoid
			(at 3.4 0 270)
			(size 2.5 5.3)
			(layers "F.Cu" "F.Mask" "F.Paste")
			(net 2 "GND")
			(pintype "passive")
		)
	)
	(footprint "antmicro-footprints:R_0402_1005Metric"
		(layer "F.Cu")
		(at 97.826 72.35 90)
		(descr "Resistor SMD 0402")
		(tags "resistor SMD 0402")
		(property "Reference" "R34"
			(at -10 0.55 0)
			(layer "B.SilkS")
			(effects
				(font
					(size 0.7 0.7)
					(thickness 0.15)
				)
				(justify left bottom mirror)
			)
		)
		(property "Value" "R_1k2_0402"
			(at -1.011843 1.772047 90)
			(layer "F.Fab")
			(effects
				(font
					(size 0.7 0.7)
					(thickness 0.15)
				)
				(justify left bottom)
			)
		)
		(property "Datasheet" "https://www.bourns.com/docs/product-datasheets/cr.pdf"
			(at 0 0 90)
			(layer "F.Fab")
			(hide yes)
			(effects
				(font
					(size 1.27 1.27)
					(thickness 0.15)
				)
			)
		)
		(property "Description" "SMD Chip Resistor, 1.2 kohm, ± 1%, 62.5 mW, 0402 [1005 Metric], Thick Film, General Purpose"
			(at 0 0 90)
			(layer "F.Fab")
			(hide yes)
			(effects
				(font
					(size 1.27 1.27)
					(thickness 0.15)
				)
			)
		)
		(property "MPN" "CR0402-FX-1201GLF"
			(at 0 0 90)
			(unlocked yes)
			(layer "F.Fab")
			(hide yes)
			(effects
				(font
					(size 1 1)
					(thickness 0.15)
				)
			)
		)
		(property "Manufacturer" "Bourns"
			(at 0 0 90)
			(unlocked yes)
			(layer "F.Fab")
			(hide yes)
			(effects
				(font
					(size 1 1)
					(thickness 0.15)
				)
			)
		)
		(property "License" "Apache-2.0"
			(at 0 0 90)
			(unlocked yes)
			(layer "F.Fab")
			(hide yes)
			(effects
				(font
					(size 1 1)
					(thickness 0.15)
				)
			)
		)
		(property "Author" "Antmicro"
			(at 0 0 90)
			(unlocked yes)
			(layer "F.Fab")
			(hide yes)
			(effects
				(font
					(size 1 1)
					(thickness 0.15)
				)
			)
		)
		(property "Val" "1k2"
			(at 0 0 90)
			(unlocked yes)
			(layer "F.Fab")
			(hide yes)
			(effects
				(font
					(size 1 1)
					(thickness 0.15)
				)
			)
		)
		(property "Tolerance" "1%"
			(at 0 0 90)
			(unlocked yes)
			(layer "F.Fab")
			(hide yes)
			(effects
				(font
					(size 1 1)
					(thickness 0.15)
				)
			)
		)
		(sheetname "/USB PD/")
		(sheetfile "usb_pd.kicad_sch")
		(attr smd)
		(fp_rect
			(start -0.925 -0.47)
			(end 0.925 0.47)
			(stroke
				(width 0.05)
				(type default)
			)
			(fill no)
			(layer "F.CrtYd")
		)
		(fp_rect
			(start -0.5 -0.25)
			(end 0.5 0.25)
			(stroke
				(width 0.15)
				(type solid)
			)
			(fill no)
			(layer "F.Fab")
		)
		(pad "1" smd roundrect
			(at -0.48 0 90)
			(size 0.59 0.64)
			(layers "F.Cu" "F.Mask" "F.Paste")
			(roundrect_rratio 0.25)
			(net 64 "Net-(D3-A)")
			(pintype "passive")
		)
		(pad "2" smd roundrect
			(at 0.48 0 90)
			(size 0.59 0.64)
			(layers "F.Cu" "F.Mask" "F.Paste")
			(roundrect_rratio 0.25)
			(net 6 "VBUS")
			(pintype "passive")
		)
	)
	(footprint "antmicro-footprints:R_0402_1005Metric"
		(layer "F.Cu")
		(at 86.026 78.525 180)
		(descr "Resistor SMD 0402")
		(tags "resistor SMD 0402")
		(property "Reference" "R33"
			(at 1.057 -2.141 0)
			(layer "F.SilkS")
			(effects
				(font
					(size 0.7 0.7)
					(thickness 0.15)
				)
				(justify left bottom)
			)
		)
		(property "Value" "R_100R_0402"
			(at -1.011843 1.772047 0)
			(layer "F.Fab")
			(effects
				(font
					(size 0.7 0.7)
					(thickness 0.15)
				)
				(justify right bottom)
			)
		)
		(property "Datasheet" "https://www.bourns.com/docs/product-datasheets/cr.pdf"
			(at 0 0 180)
			(layer "F.Fab")
			(hide yes)
			(effects
				(font
					(size 1.27 1.27)
					(thickness 0.15)
				)
			)
		)
		(property "Description" "SMD Chip Resistor, 100 ohm, ± 1%, 62.5 mW, 0402 [1005 Metric], Thick Film, General Purpose"
			(at 0 0 180)
			(layer "F.Fab")
			(hide yes)
			(effects
				(font
					(size 1.27 1.27)
					(thickness 0.15)
				)
			)
		)
		(property "MPN" "CR0402-FX-1000GLF"
			(at 0 0 180)
			(unlocked yes)
			(layer "F.Fab")
			(hide yes)
			(effects
				(font
					(size 1 1)
					(thickness 0.15)
				)
			)
		)
		(property "Manufacturer" "Bourns"
			(at 0 0 180)
			(unlocked yes)
			(layer "F.Fab")
			(hide yes)
			(effects
				(font
					(size 1 1)
					(thickness 0.15)
				)
			)
		)
		(property "License" "Apache-2.0"
			(at 0 0 180)
			(unlocked yes)
			(layer "F.Fab")
			(hide yes)
			(effects
				(font
					(size 1 1)
					(thickness 0.15)
				)
			)
		)
		(property "Author" "Antmicro"
			(at 0 0 180)
			(unlocked yes)
			(layer "F.Fab")
			(hide yes)
			(effects
				(font
					(size 1 1)
					(thickness 0.15)
				)
			)
		)
		(property "Val" "100R"
			(at 0 0 180)
			(unlocked yes)
			(layer "F.Fab")
			(hide yes)
			(effects
				(font
					(size 1 1)
					(thickness 0.15)
				)
			)
		)
		(property "Tolerance" "1%"
			(at 0 0 180)
			(unlocked yes)
			(layer "F.Fab")
			(hide yes)
			(effects
				(font
					(size 1 1)
					(thickness 0.15)
				)
			)
		)
		(sheetname "/USB PD/")
		(sheetfile "usb_pd.kicad_sch")
		(attr smd)
		(fp_rect
			(start -0.925 -0.47)
			(end 0.925 0.47)
			(stroke
				(width 0.05)
				(type default)
			)
			(fill no)
			(layer "F.CrtYd")
		)
		(fp_rect
			(start -0.5 -0.25)
			(end 0.5 0.25)
			(stroke
				(width 0.15)
				(type solid)
			)
			(fill no)
			(layer "F.Fab")
		)
		(pad "1" smd roundrect
			(at -0.48 0 180)
			(size 0.59 0.64)
			(layers "F.Cu" "F.Mask" "F.Paste")
			(roundrect_rratio 0.25)
			(net 7 "Net-(Q1-G)")
			(pintype "passive")
		)
		(pad "2" smd roundrect
			(at 0.48 0 180)
			(size 0.59 0.64)
			(layers "F.Cu" "F.Mask" "F.Paste")
			(roundrect_rratio 0.25)
			(net 20 "Net-(C19-Pad1)")
			(pintype "passive")
		)
	)
	(footprint "antmicro-footprints:C_0402_1005Metric"
		(layer "F.Cu")
		(at 100 79.577 180)
		(descr "Capacitor SMD 0402")
		(tags "capacitor SMD 0402")
		(property "Reference" "C1"
			(at -1.092 -0.433 0)
			(layer "F.SilkS")
			(effects
				(font
					(size 0.7 0.7)
					(thickness 0.15)
				)
				(justify left bottom)
			)
		)
		(property "Value" "C_1u_25V_0402"
			(at -1.022927 2.155213 0)
			(layer "F.Fab")
			(effects
				(font
					(size 0.7 0.7)
					(thickness 0.15)
				)
				(justify right bottom)
			)
		)
		(property "Datasheet" "https://www.murata.com/products/productdetail?partno=GRM155R61E105KE11%23"
			(at 0 0 180)
			(layer "F.Fab")
			(hide yes)
			(effects
				(font
					(size 1.27 1.27)
					(thickness 0.15)
				)
			)
		)
		(property "Description" "SMD Multilayer Ceramic Capacitor, 1 µF, 25 V, 0402 [1005 Metric], ± 10%, X5R, GRM Series"
			(at 0 0 180)
			(layer "F.Fab")
			(hide yes)
			(effects
				(font
					(size 1.27 1.27)
					(thickness 0.15)
				)
			)
		)
		(property "MPN" "GRM155R61E105KE11J"
			(at 0 0 180)
			(unlocked yes)
			(layer "F.Fab")
			(hide yes)
			(effects
				(font
					(size 1 1)
					(thickness 0.15)
				)
			)
		)
		(property "Manufacturer" "Murata"
			(at 0 0 180)
			(unlocked yes)
			(layer "F.Fab")
			(hide yes)
			(effects
				(font
					(size 1 1)
					(thickness 0.15)
				)
			)
		)
		(property "License" "Apache-2.0"
			(at 0 0 180)
			(unlocked yes)
			(layer "F.Fab")
			(hide yes)
			(effects
				(font
					(size 1 1)
					(thickness 0.15)
				)
			)
		)
		(property "Author" "Antmicro"
			(at 0 0 180)
			(unlocked yes)
			(layer "F.Fab")
			(hide yes)
			(effects
				(font
					(size 1 1)
					(thickness 0.15)
				)
			)
		)
		(property "Val" "1u"
			(at 0 0 180)
			(unlocked yes)
			(layer "F.Fab")
			(hide yes)
			(effects
				(font
					(size 1 1)
					(thickness 0.15)
				)
			)
		)
		(property "Voltage" "25V"
			(at 0 0 180)
			(unlocked yes)
			(layer "F.Fab")
			(hide yes)
			(effects
				(font
					(size 1 1)
					(thickness 0.15)
				)
			)
		)
		(property "Dielectric" "X5R"
			(at 0 0 180)
			(unlocked yes)
			(layer "F.Fab")
			(hide yes)
			(effects
				(font
					(size 1 1)
					(thickness 0.15)
				)
			)
		)
		(sheetname "/DC-DC Converters/")
		(sheetfile "dc-dc_converters.kicad_sch")
		(attr smd)
		(fp_rect
			(start -0.925 -0.47)
			(end 0.925 0.47)
			(stroke
				(width 0.05)
				(type default)
			)
			(fill no)
			(layer "F.CrtYd")
		)
		(fp_line
			(start 0.504 0.248)
			(end -0.494 0.248)
			(stroke
				(width 0.15)
				(type solid)
			)
			(layer "F.Fab")
		)
		(fp_line
			(start 0.504 -0.25)
			(end 0.504 0.248)
			(stroke
				(width 0.15)
				(type solid)
			)
			(layer "F.Fab")
		)
		(fp_line
			(start -0.494 0.248)
			(end -0.494 -0.25)
			(stroke
				(width 0.15)
				(type solid)
			)
			(layer "F.Fab")
		)
		(fp_line
			(start -0.494 -0.25)
			(end 0.504 -0.25)
			(stroke
				(width 0.15)
				(type solid)
			)
			(layer "F.Fab")
		)
		(pad "1" smd roundrect
			(at -0.48 0 180)
			(size 0.59 0.64)
			(layers "F.Cu" "F.Mask" "F.Paste")
			(roundrect_rratio 0.25)
			(net 2 "GND")
			(pintype "passive")
		)
		(pad "2" smd roundrect
			(at 0.48 0 180)
			(size 0.59 0.64)
			(layers "F.Cu" "F.Mask" "F.Paste")
			(roundrect_rratio 0.25)
			(net 10 "/DC-DC Converters/VDD_12V_DCDC")
			(pintype "passive")
		)
	)
	(footprint "antmicro-footprints:R_0402_1005Metric"
		(layer "F.Cu")
		(at 88.9 68.63 -90)
		(descr "Resistor SMD 0402")
		(tags "resistor SMD 0402")
		(property "Reference" "R38"
			(at -1.205 -1.251 270)
			(layer "F.SilkS")
			(effects
				(font
					(size 0.7 0.7)
					(thickness 0.15)
				)
				(justify right bottom)
			)
		)
		(property "Value" "R_0R_0402"
			(at -1.011843 1.772047 90)
			(layer "F.Fab")
			(effects
				(font
					(size 0.7 0.7)
					(thickness 0.15)
				)
				(justify right bottom)
			)
		)
		(property "Datasheet" "https://industrial.panasonic.com/cdbs/www-data/pdf/RDA0000/AOA0000C301.pdf"
			(at 0 0 270)
			(layer "F.Fab")
			(hide yes)
			(effects
				(font
					(size 1.27 1.27)
					(thickness 0.15)
				)
			)
		)
		(property "Description" "SMD Chip Resistor, Jumper, 0 ohm, 100 mW, 0402 [1005 Metric], Thick Film, General Purpose"
			(at 0 0 270)
			(layer "F.Fab")
			(hide yes)
			(effects
				(font
					(size 1.27 1.27)
					(thickness 0.15)
				)
			)
		)
		(property "MPN" "ERJ2GE0R00X"
			(at 0 0 270)
			(unlocked yes)
			(layer "F.Fab")
			(hide yes)
			(effects
				(font
					(size 1 1)
					(thickness 0.15)
				)
			)
		)
		(property "Manufacturer" "Panasonic"
			(at 0 0 270)
			(unlocked yes)
			(layer "F.Fab")
			(hide yes)
			(effects
				(font
					(size 1 1)
					(thickness 0.15)
				)
			)
		)
		(property "License" "Apache-2.0"
			(at 0 0 270)
			(unlocked yes)
			(layer "F.Fab")
			(hide yes)
			(effects
				(font
					(size 1 1)
					(thickness 0.15)
				)
			)
		)
		(property "Author" "Antmicro"
			(at 0 0 270)
			(unlocked yes)
			(layer "F.Fab")
			(hide yes)
			(effects
				(font
					(size 1 1)
					(thickness 0.15)
				)
			)
		)
		(property "Val" "0R"
			(at 0 0 270)
			(unlocked yes)
			(layer "F.Fab")
			(hide yes)
			(effects
				(font
					(size 1 1)
					(thickness 0.15)
				)
			)
		)
		(property "Tolerance" ""
			(at 0 0 270)
			(unlocked yes)
			(layer "F.Fab")
			(hide yes)
			(effects
				(font
					(size 1 1)
					(thickness 0.15)
				)
			)
		)
		(property "Current" "1A"
			(at 0 0 270)
			(unlocked yes)
			(layer "F.Fab")
			(hide yes)
			(effects
				(font
					(size 1 1)
					(thickness 0.15)
				)
			)
		)
		(sheetname "/USB PD/")
		(sheetfile "usb_pd.kicad_sch")
		(attr smd exclude_from_pos_files exclude_from_bom dnp)
		(fp_rect
			(start -0.925 -0.47)
			(end 0.925 0.47)
			(stroke
				(width 0.05)
				(type default)
			)
			(fill no)
			(layer "F.CrtYd")
		)
		(fp_rect
			(start -0.5 -0.25)
			(end 0.5 0.25)
			(stroke
				(width 0.15)
				(type solid)
			)
			(fill no)
			(layer "F.Fab")
		)
		(pad "1" smd roundrect
			(at -0.48 0 270)
			(size 0.59 0.64)
			(layers "F.Cu" "F.Mask" "F.Paste")
			(roundrect_rratio 0.25)
			(net 61 "/USB PD/QWIIC_VCC")
			(pintype "passive")
		)
		(pad "2" smd roundrect
			(at 0.48 0 270)
			(size 0.59 0.64)
			(layers "F.Cu" "F.Mask" "F.Paste")
			(roundrect_rratio 0.25)
			(net 1 "+3V3")
			(pintype "passive")
		)
	)
	(footprint "antmicro-footprints:R_0402_1005Metric"
		(layer "F.Cu")
		(at 100.276 72.35 90)
		(descr "Resistor SMD 0402")
		(tags "resistor SMD 0402")
		(property "Reference" "R26"
			(at -7.9 -1.8 0)
			(layer "B.SilkS")
			(effects
				(font
					(size 0.7 0.7)
					(thickness 0.15)
				)
				(justify left bottom mirror)
			)
		)
		(property "Value" "R_470_0402"
			(at -1.011843 1.772047 90)
			(layer "F.Fab")
			(effects
				(font
					(size 0.7 0.7)
					(thickness 0.15)
				)
				(justify left bottom)
			)
		)
		(property "Datasheet" "https://www.bourns.com/docs/product-datasheets/cr.pdf"
			(at 0 0 90)
			(layer "F.Fab")
			(hide yes)
			(effects
				(font
					(size 1.27 1.27)
					(thickness 0.15)
				)
			)
		)
		(property "Description" "SMD Chip Resistor, 470 ohm, ± 1%, 62.5 mW, 0402 [1005 Metric], Thick Film, General Purpose"
			(at 0 0 90)
			(layer "F.Fab")
			(hide yes)
			(effects
				(font
					(size 1.27 1.27)
					(thickness 0.15)
				)
			)
		)
		(property "MPN" "CR0402-FX-4700GLF"
			(at 0 0 90)
			(unlocked yes)
			(layer "F.Fab")
			(hide yes)
			(effects
				(font
					(size 1 1)
					(thickness 0.15)
				)
			)
		)
		(property "Manufacturer" "Bourns"
			(at 0 0 90)
			(unlocked yes)
			(layer "F.Fab")
			(hide yes)
			(effects
				(font
					(size 1 1)
					(thickness 0.15)
				)
			)
		)
		(property "License" "Apache-2.0"
			(at 0 0 90)
			(unlocked yes)
			(layer "F.Fab")
			(hide yes)
			(effects
				(font
					(size 1 1)
					(thickness 0.15)
				)
			)
		)
		(property "Author" "Antmicro"
			(at 0 0 90)
			(unlocked yes)
			(layer "F.Fab")
			(hide yes)
			(effects
				(font
					(size 1 1)
					(thickness 0.15)
				)
			)
		)
		(property "Val" "470R"
			(at 0 0 90)
			(unlocked yes)
			(layer "F.Fab")
			(hide yes)
			(effects
				(font
					(size 1 1)
					(thickness 0.15)
				)
			)
		)
		(property "Tolerance" "1%"
			(at 0 0 90)
			(unlocked yes)
			(layer "F.Fab")
			(hide yes)
			(effects
				(font
					(size 1 1)
					(thickness 0.15)
				)
			)
		)
		(sheetname "/USB PD/")
		(sheetfile "usb_pd.kicad_sch")
		(attr smd)
		(fp_rect
			(start -0.925 -0.47)
			(end 0.925 0.47)
			(stroke
				(width 0.05)
				(type default)
			)
			(fill no)
			(layer "F.CrtYd")
		)
		(fp_rect
			(start -0.5 -0.25)
			(end 0.5 0.25)
			(stroke
				(width 0.15)
				(type solid)
			)
			(fill no)
			(layer "F.Fab")
		)
		(pad "1" smd roundrect
			(at -0.48 0 90)
			(size 0.59 0.64)
			(layers "F.Cu" "F.Mask" "F.Paste")
			(roundrect_rratio 0.25)
			(net 67 "Net-(D7-A)")
			(pintype "passive")
		)
		(pad "2" smd roundrect
			(at 0.48 0 90)
			(size 0.59 0.64)
			(layers "F.Cu" "F.Mask" "F.Paste")
			(roundrect_rratio 0.25)
			(net 25 "+5V")
			(pintype "passive")
		)
	)
)
